# SCM (Grand Teton) — schematic netlist excerpt (pin names and nets, part order shuffled) for the footprints in the layout excerpt that follows; sources: Cadence DE-HDL packaged netlist, KiCad conversion of 12092022_DA0F0TMDCD0_F0T_Management_Board_D_brd_V3_OCP.brd

C27  Q_CAP  0.1UF 25V 10% X7R  pkg 0402  page 50 : A = LED_D22_R ; B = GND
C144  Q_CAP  0.1UF 25V 10% X7R  pkg 0402  page 46 : A = P3V3_AUX ; B = GND

(kicad_pcb
	(version 20260206)
	(generator "pcbnew")
	(generator_version "10.0")
	(general
		(thickness 1.6)
		(legacy_teardrops no)
	)
	(paper "A4")
	(title_block
		(title "12092022_DA0F0TMDCD0_F0T_Management_Board_D_brd_V3_OCP.brd")
		(comment 1 "Grand Teton / footprints 637-638 of 1440")
	)
	(layers
		(0 "F.Cu" signal "TOP")
		(4 "In1.Cu" signal "GND")
		(6 "In2.Cu" signal "IN1")
		(8 "In3.Cu" signal "GND1")
		(10 "In4.Cu" signal "IN2")
		(12 "In5.Cu" signal "VCC")
		(14 "In6.Cu" signal "VCC1")
		(16 "In7.Cu" signal "IN3")
		(18 "In8.Cu" signal "GND2")
		(20 "In9.Cu" signal "IN4")
		(22 "In10.Cu" signal "GND3")
		(2 "B.Cu" signal "BOTTOM")
		(9 "F.Adhes" user "F.Adhesive")
		(11 "B.Adhes" user "B.Adhesive")
		(13 "F.Paste" user "Package Geometry/Pastemask Top")
		(15 "B.Paste" user "Package Geometry/Pastemask Bottom")
		(5 "F.SilkS" user "Ref Des/Silkscreen Top")
		(7 "B.SilkS" user "Ref Des/Silkscreen Bottom")
		(1 "F.Mask" user "Board Geometry/Soldermask Top")
		(3 "B.Mask" user "Board Geometry/Soldermask Bottom")
		(17 "Dwgs.User" user "User.Drawings")
		(19 "Cmts.User" user "User.Comments")
		(21 "Eco1.User" user "User.Eco1")
		(23 "Eco2.User" user "User.Eco2")
		(25 "Edge.Cuts" user "Board Geometry/Outline")
		(27 "Margin" user)
		(31 "F.CrtYd" user "Package Geometry/Place Bound Top")
		(29 "B.CrtYd" user "Package Geometry/Place Bound Bottom")
		(35 "F.Fab" user "Ref Des/Assembly Top")
		(33 "B.Fab" user "Ref Des/Assembly Bottom")
	)
	(footprint ""
		(layer "F.Cu")
		(at 74.09815 -92.204032 180)
		(property "Reference" "C144"
			(at 0 0 180)
			(layer "F.SilkS")
			(hide yes)
			(effects
				(font
					(size 1.27 1.27)
				)
			)
		)
		(property "Value" ""
			(at 0 0 180)
			(layer "F.Fab")
			(effects
				(font
					(size 1.27 1.27)
				)
			)
		)
		(duplicate_pad_numbers_are_jumpers no)
		(fp_line
			(start 0.7874 0.4064)
			(end -0.7874 0.4064)
			(stroke
				(width 0.1524)
				(type default)
			)
			(layer "F.SilkS")
		)
		(fp_line
			(start 0.7874 -0.4064)
			(end 0.7874 0.4064)
			(stroke
				(width 0.1524)
				(type default)
			)
			(layer "F.SilkS")
		)
		(fp_line
			(start -0.7874 0.4064)
			(end -0.7874 -0.4064)
			(stroke
				(width 0.1524)
				(type default)
			)
			(layer "F.SilkS")
		)
		(fp_line
			(start -0.7874 -0.4064)
			(end 0.7874 -0.4064)
			(stroke
				(width 0.1524)
				(type default)
			)
			(layer "F.SilkS")
		)
		(fp_line
			(start 0.67945 0.3048)
			(end 0.120396 0.3048)
			(stroke
				(width 0.1)
				(type default)
			)
			(layer "F.Fab")
		)
		(fp_line
			(start 0.67945 -0.3048)
			(end 0.67945 0.3048)
			(stroke
				(width 0.1)
				(type default)
			)
			(layer "F.Fab")
		)
		(fp_line
			(start 0.12065 -0.2794)
			(end 0.12065 -0.3048)
			(stroke
				(width 0.1)
				(type default)
			)
			(layer "F.Fab")
		)
		(fp_line
			(start 0.12065 -0.3048)
			(end 0.67945 -0.3048)
			(stroke
				(width 0.1)
				(type default)
			)
			(layer "F.Fab")
		)
		(fp_line
			(start 0.120396 0.3048)
			(end 0.120396 0.2794)
			(stroke
				(width 0.1)
				(type default)
			)
			(layer "F.Fab")
		)
		(fp_line
			(start 0.120396 0.2794)
			(end -0.12065 0.2794)
			(stroke
				(width 0.1)
				(type default)
			)
			(layer "F.Fab")
		)
		(fp_line
			(start -0.12065 0.3048)
			(end -0.67945 0.3048)
			(stroke
				(width 0.1)
				(type default)
			)
			(layer "F.Fab")
		)
		(fp_line
			(start -0.12065 0.2794)
			(end -0.12065 0.3048)
			(stroke
				(width 0.1)
				(type default)
			)
			(layer "F.Fab")
		)
		(fp_line
			(start -0.12065 -0.2794)
			(end 0.12065 -0.2794)
			(stroke
				(width 0.1)
				(type default)
			)
			(layer "F.Fab")
		)
		(fp_line
			(start -0.12065 -0.305054)
			(end -0.12065 -0.2794)
			(stroke
				(width 0.1)
				(type default)
			)
			(layer "F.Fab")
		)
		(fp_line
			(start -0.67945 0.3048)
			(end -0.67945 -0.305054)
			(stroke
				(width 0.1)
				(type default)
			)
			(layer "F.Fab")
		)
		(fp_line
			(start -0.67945 -0.305054)
			(end -0.12065 -0.305054)
			(stroke
				(width 0.1)
				(type default)
			)
			(layer "F.Fab")
		)
		(pad "1" smd circle
			(at -0.40005 0 180)
			(size 0 0)
			(layers "F.Cu" "F.Mask" "F.Paste")
			(net "P3V3_AUX")
		)
		(pad "2" smd circle
			(at 0.40005 0 180)
			(size 0 0)
			(layers "F.Cu" "F.Mask" "F.Paste")
			(net "GND")
		)
	)
	(footprint ""
		(layer "F.Cu")
		(at 59.182 -10.922 90)
		(property "Reference" "C27"
			(at 0 0 90)
			(layer "F.SilkS")
			(hide yes)
			(effects
				(font
					(size 1.27 1.27)
				)
			)
		)
		(property "Value" ""
			(at 0 0 90)
			(layer "F.Fab")
			(effects
				(font
					(size 1.27 1.27)
				)
			)
		)
		(duplicate_pad_numbers_are_jumpers no)
		(fp_line
			(start -0.492506 -0.4064)
			(end 0.421894 -0.4064)
			(stroke
				(width 0.1524)
				(type default)
			)
			(layer "F.SilkS")
		)
		(fp_line
			(start 0.7874 -0.077216)
			(end 0.7874 0.4064)
			(stroke
				(width 0.1524)
				(type default)
			)
			(layer "F.SilkS")
		)
		(fp_line
			(start 0.7874 0.4064)
			(end -0.7874 0.4064)
			(stroke
				(width 0.1524)
				(type default)
			)
			(layer "F.SilkS")
		)
		(fp_line
			(start -0.7874 0.4064)
			(end -0.7874 -0.039116)
			(stroke
				(width 0.1524)
				(type default)
			)
			(layer "F.SilkS")
		)
		(fp_line
			(start -0.12065 -0.305054)
			(end -0.12065 -0.2794)
			(stroke
				(width 0.1)
				(type default)
			)
			(layer "F.Fab")
		)
		(fp_line
			(start -0.67945 -0.305054)
			(end -0.12065 -0.305054)
			(stroke
				(width 0.1)
				(type default)
			)
			(layer "F.Fab")
		)
		(fp_line
			(start 0.67945 -0.3048)
			(end 0.67945 0.3048)
			(stroke
				(width 0.1)
				(type default)
			)
			(layer "F.Fab")
		)
		(fp_line
			(start 0.12065 -0.3048)
			(end 0.67945 -0.3048)
			(stroke
				(width 0.1)
				(type default)
			)
			(layer "F.Fab")
		)
		(fp_line
			(start 0.12065 -0.2794)
			(end 0.12065 -0.3048)
			(stroke
				(width 0.1)
				(type default)
			)
			(layer "F.Fab")
		)
		(fp_line
			(start -0.12065 -0.2794)
			(end 0.12065 -0.2794)
			(stroke
				(width 0.1)
				(type default)
			)
			(layer "F.Fab")
		)
		(fp_line
			(start 0.120396 0.2794)
			(end -0.12065 0.2794)
			(stroke
				(width 0.1)
				(type default)
			)
			(layer "F.Fab")
		)
		(fp_line
			(start -0.12065 0.2794)
			(end -0.12065 0.3048)
			(stroke
				(width 0.1)
				(type default)
			)
			(layer "F.Fab")
		)
		(fp_line
			(start 0.67945 0.3048)
			(end 0.120396 0.3048)
			(stroke
				(width 0.1)
				(type default)
			)
			(layer "F.Fab")
		)
		(fp_line
			(start 0.120396 0.3048)
			(end 0.120396 0.2794)
			(stroke
				(width 0.1)
				(type default)
			)
			(layer "F.Fab")
		)
		(fp_line
			(start -0.12065 0.3048)
			(end -0.67945 0.3048)
			(stroke
				(width 0.1)
				(type default)
			)
			(layer "F.Fab")
		)
		(fp_line
			(start -0.67945 0.3048)
			(end -0.67945 -0.305054)
			(stroke
				(width 0.1)
				(type default)
			)
			(layer "F.Fab")
		)
		(pad "1" smd circle
			(at -0.40005 0 90)
			(size 0 0)
			(layers "F.Cu" "F.Mask" "F.Paste")
			(net "LED_D22_R")
		)
		(pad "2" smd circle
			(at 0.40005 0 90)
			(size 0 0)
			(layers "F.Cu" "F.Mask" "F.Paste")
			(net "GND")
		)
	)
)
